(kicad_pcb
	(version 20260206)
	(generator "pcbnew")
	(generator_version "10.0")
	(general
		(thickness 1.6)
		(legacy_teardrops no)
	)
	(paper "A4")
	(title_block
		(title "03242023_DA0F0TMBIJ0_F0T_Motherboard_J_brd_V01_OCP.brd")
		(comment 1 "Grand Teton / footprints 3658-3664 of 6105")
	)
	(layers
		(0 "F.Cu" signal "TOP")
		(4 "In1.Cu" signal "GND")
		(6 "In2.Cu" signal "IN1")
		(8 "In3.Cu" signal "GND1")
		(10 "In4.Cu" signal "IN2")
		(12 "In5.Cu" signal "GND2")
		(14 "In6.Cu" signal "IN3")
		(16 "In7.Cu" signal "GND3")
		(18 "In8.Cu" signal "VCC")
		(20 "In9.Cu" signal "VCC1")
		(22 "In10.Cu" signal "GND4")
		(24 "In11.Cu" signal "IN4")
		(26 "In12.Cu" signal "GND5")
		(28 "In13.Cu" signal "IN5")
		(30 "In14.Cu" signal "GND6")
		(32 "In15.Cu" signal "IN6")
		(34 "In16.Cu" signal "GND7")
		(2 "B.Cu" signal "BOTTOM")
		(9 "F.Adhes" user "F.Adhesive")
		(11 "B.Adhes" user "B.Adhesive")
		(13 "F.Paste" user "Package Geometry/Pastemask Top")
		(15 "B.Paste" user "Package Geometry/Pastemask Bottom")
		(5 "F.SilkS" user "Ref Des/Silkscreen Top")
		(7 "B.SilkS" user "Ref Des/Silkscreen Bottom")
		(1 "F.Mask" user "Board Geometry/Soldermask Top")
		(3 "B.Mask" user "Board Geometry/Soldermask Bottom")
		(17 "Dwgs.User" user "User.Drawings")
		(19 "Cmts.User" user "User.Comments")
		(21 "Eco1.User" user "User.Eco1")
		(23 "Eco2.User" user "User.Eco2")
		(25 "Edge.Cuts" user "Board Geometry/Outline")
		(27 "Margin" user)
		(31 "F.CrtYd" user "Package Geometry/Place Bound Top")
		(29 "B.CrtYd" user "Package Geometry/Place Bound Bottom")
		(35 "F.Fab" user "Ref Des/Assembly Top")
		(33 "B.Fab" user "Ref Des/Assembly Bottom")
	)
	(footprint ""
		(layer "F.Cu")
		(at 211.210906 -16.343122 -90)
		(property "Reference" "R1141"
			(at 0 0 270)
			(layer "F.SilkS")
			(hide yes)
			(effects
				(font
					(size 1.27 1.27)
				)
			)
		)
		(property "Value" ""
			(at 0 0 270)
			(layer "F.Fab")
			(effects
				(font
					(size 1.27 1.27)
				)
			)
		)
		(duplicate_pad_numbers_are_jumpers no)
		(fp_line
			(start -0.7874 0.4064)
			(end -0.7874 -0.4064)
			(stroke
				(width 0.1524)
				(type default)
			)
			(layer "F.SilkS")
		)
		(fp_line
			(start 0.7874 0.4064)
			(end -0.7874 0.4064)
			(stroke
				(width 0.1524)
				(type default)
			)
			(layer "F.SilkS")
		)
		(fp_line
			(start -0.7874 -0.4064)
			(end 0.7874 -0.4064)
			(stroke
				(width 0.1524)
				(type default)
			)
			(layer "F.SilkS")
		)
		(fp_line
			(start 0.7874 -0.4064)
			(end 0.7874 0.4064)
			(stroke
				(width 0.1524)
				(type default)
			)
			(layer "F.SilkS")
		)
		(fp_line
			(start -0.67945 0.3048)
			(end -0.67945 -0.305054)
			(stroke
				(width 0.1)
				(type default)
			)
			(layer "F.Fab")
		)
		(fp_line
			(start -0.12065 0.3048)
			(end -0.67945 0.3048)
			(stroke
				(width 0.1)
				(type default)
			)
			(layer "F.Fab")
		)
		(fp_line
			(start 0.120396 0.3048)
			(end 0.120396 0.2794)
			(stroke
				(width 0.1)
				(type default)
			)
			(layer "F.Fab")
		)
		(fp_line
			(start 0.67945 0.3048)
			(end 0.120396 0.3048)
			(stroke
				(width 0.1)
				(type default)
			)
			(layer "F.Fab")
		)
		(fp_line
			(start -0.12065 0.2794)
			(end -0.12065 0.3048)
			(stroke
				(width 0.1)
				(type default)
			)
			(layer "F.Fab")
		)
		(fp_line
			(start 0.120396 0.2794)
			(end -0.12065 0.2794)
			(stroke
				(width 0.1)
				(type default)
			)
			(layer "F.Fab")
		)
		(fp_line
			(start -0.12065 -0.2794)
			(end 0.12065 -0.2794)
			(stroke
				(width 0.1)
				(type default)
			)
			(layer "F.Fab")
		)
		(fp_line
			(start 0.12065 -0.2794)
			(end 0.12065 -0.3048)
			(stroke
				(width 0.1)
				(type default)
			)
			(layer "F.Fab")
		)
		(fp_line
			(start 0.12065 -0.3048)
			(end 0.67945 -0.3048)
			(stroke
				(width 0.1)
				(type default)
			)
			(layer "F.Fab")
		)
		(fp_line
			(start 0.67945 -0.3048)
			(end 0.67945 0.3048)
			(stroke
				(width 0.1)
				(type default)
			)
			(layer "F.Fab")
		)
		(fp_line
			(start -0.67945 -0.305054)
			(end -0.12065 -0.305054)
			(stroke
				(width 0.1)
				(type default)
			)
			(layer "F.Fab")
		)
		(fp_line
			(start -0.12065 -0.305054)
			(end -0.12065 -0.2794)
			(stroke
				(width 0.1)
				(type default)
			)
			(layer "F.Fab")
		)
		(pad "1" smd circle
			(at -0.40005 0 270)
			(size 0 0)
			(layers "F.Cu" "F.Mask" "F.Paste")
			(net "CLK_50M_NCSI_OCP_1")
		)
		(pad "2" smd circle
			(at 0.40005 0 270)
			(size 0 0)
			(layers "F.Cu" "F.Mask" "F.Paste")
			(net "CLK_50M_NCSI_OCP_SFF")
		)
	)
	(footprint ""
		(layer "F.Cu")
		(at 114.70132 -409.428442)
		(property "Reference" "R4494"
			(at 0 0 0)
			(layer "F.SilkS")
			(hide yes)
			(effects
				(font
					(size 1.27 1.27)
				)
			)
		)
		(property "Value" ""
			(at 0 0 0)
			(layer "F.Fab")
			(effects
				(font
					(size 1.27 1.27)
				)
			)
		)
		(duplicate_pad_numbers_are_jumpers no)
		(fp_line
			(start -0.7874 -0.4064)
			(end 0.7874 -0.4064)
			(stroke
				(width 0.1524)
				(type default)
			)
			(layer "F.SilkS")
		)
		(fp_line
			(start -0.7874 0.4064)
			(end -0.7874 -0.4064)
			(stroke
				(width 0.1524)
				(type default)
			)
			(layer "F.SilkS")
		)
		(fp_line
			(start 0.7874 -0.4064)
			(end 0.7874 0.4064)
			(stroke
				(width 0.1524)
				(type default)
			)
			(layer "F.SilkS")
		)
		(fp_line
			(start 0.7874 0.4064)
			(end -0.7874 0.4064)
			(stroke
				(width 0.1524)
				(type default)
			)
			(layer "F.SilkS")
		)
		(fp_line
			(start -0.67945 -0.305054)
			(end -0.12065 -0.305054)
			(stroke
				(width 0.1)
				(type default)
			)
			(layer "F.Fab")
		)
		(fp_line
			(start -0.67945 0.3048)
			(end -0.67945 -0.305054)
			(stroke
				(width 0.1)
				(type default)
			)
			(layer "F.Fab")
		)
		(fp_line
			(start -0.12065 -0.305054)
			(end -0.12065 -0.2794)
			(stroke
				(width 0.1)
				(type default)
			)
			(layer "F.Fab")
		)
		(fp_line
			(start -0.12065 -0.2794)
			(end 0.12065 -0.2794)
			(stroke
				(width 0.1)
				(type default)
			)
			(layer "F.Fab")
		)
		(fp_line
			(start -0.12065 0.2794)
			(end -0.12065 0.3048)
			(stroke
				(width 0.1)
				(type default)
			)
			(layer "F.Fab")
		)
		(fp_line
			(start -0.12065 0.3048)
			(end -0.67945 0.3048)
			(stroke
				(width 0.1)
				(type default)
			)
			(layer "F.Fab")
		)
		(fp_line
			(start 0.120396 0.2794)
			(end -0.12065 0.2794)
			(stroke
				(width 0.1)
				(type default)
			)
			(layer "F.Fab")
		)
		(fp_line
			(start 0.120396 0.3048)
			(end 0.120396 0.2794)
			(stroke
				(width 0.1)
				(type default)
			)
			(layer "F.Fab")
		)
		(fp_line
			(start 0.12065 -0.3048)
			(end 0.67945 -0.3048)
			(stroke
				(width 0.1)
				(type default)
			)
			(layer "F.Fab")
		)
		(fp_line
			(start 0.12065 -0.2794)
			(end 0.12065 -0.3048)
			(stroke
				(width 0.1)
				(type default)
			)
			(layer "F.Fab")
		)
		(fp_line
			(start 0.67945 -0.3048)
			(end 0.67945 0.3048)
			(stroke
				(width 0.1)
				(type default)
			)
			(layer "F.Fab")
		)
		(fp_line
			(start 0.67945 0.3048)
			(end 0.120396 0.3048)
			(stroke
				(width 0.1)
				(type default)
			)
			(layer "F.Fab")
		)
		(pad "1" smd circle
			(at -0.40005 0)
			(size 0 0)
			(layers "F.Cu" "F.Mask" "F.Paste")
			(net "FM_9ZXL045_3_OE_N")
		)
		(pad "2" smd circle
			(at 0.40005 0)
			(size 0 0)
			(layers "F.Cu" "F.Mask" "F.Paste")
			(net "P3V3")
		)
	)
	(footprint ""
		(layer "F.Cu")
		(at 47.159418 -178.060604 90)
		(property "Reference" "PC432"
			(at 0 0 90)
			(layer "F.SilkS")
			(hide yes)
			(effects
				(font
					(size 1.27 1.27)
				)
			)
		)
		(property "Value" ""
			(at 0 0 90)
			(layer "F.Fab")
			(effects
				(font
					(size 1.27 1.27)
				)
			)
		)
		(duplicate_pad_numbers_are_jumpers no)
		(fp_line
			(start 1.524 -0.762)
			(end 1.524 0.762)
			(stroke
				(width 0.1524)
				(type default)
			)
			(layer "F.SilkS")
		)
		(fp_line
			(start -1.524 -0.762)
			(end 1.524 -0.762)
			(stroke
				(width 0.1524)
				(type default)
			)
			(layer "F.SilkS")
		)
		(fp_line
			(start 1.524 0.762)
			(end -1.524 0.762)
			(stroke
				(width 0.1524)
				(type default)
			)
			(layer "F.SilkS")
		)
		(fp_line
			(start -1.524 0.762)
			(end -1.524 -0.762)
			(stroke
				(width 0.1524)
				(type default)
			)
			(layer "F.SilkS")
		)
		(fp_line
			(start 1.1049 -0.724916)
			(end -1.1049 -0.724916)
			(stroke
				(width 0.1)
				(type default)
			)
			(layer "F.Fab")
		)
		(fp_line
			(start -1.1049 -0.724916)
			(end -1.1049 0.724916)
			(stroke
				(width 0.1)
				(type default)
			)
			(layer "F.Fab")
		)
		(fp_line
			(start 1.1049 0.724916)
			(end 1.1049 -0.724916)
			(stroke
				(width 0.1)
				(type default)
			)
			(layer "F.Fab")
		)
		(fp_line
			(start -1.1049 0.724916)
			(end 1.1049 0.724916)
			(stroke
				(width 0.1)
				(type default)
			)
			(layer "F.Fab")
		)
		(pad "1" smd rect
			(at -0.889 0 270)
			(size 1.016 1.27)
			(layers "F.Cu" "F.Mask" "F.Paste")
			(net "SW_P12V_PVCCINFAON_CPU1_FLT")
		)
		(pad "2" smd rect
			(at 0.889 0 270)
			(size 1.016 1.27)
			(layers "F.Cu" "F.Mask" "F.Paste")
			(net "GND")
		)
	)
	(footprint ""
		(layer "F.Cu")
		(at 173.810168 -358.15778 -90)
		(property "Reference" "PC401"
			(at 0 0 270)
			(layer "F.SilkS")
			(hide yes)
			(effects
				(font
					(size 1.27 1.27)
				)
			)
		)
		(property "Value" ""
			(at 0 0 270)
			(layer "F.Fab")
			(effects
				(font
					(size 1.27 1.27)
				)
			)
		)
		(duplicate_pad_numbers_are_jumpers no)
		(fp_line
			(start -0.7874 0.4064)
			(end -0.7874 -0.4064)
			(stroke
				(width 0.1524)
				(type default)
			)
			(layer "F.SilkS")
		)
		(fp_line
			(start 0.7874 0.4064)
			(end -0.7874 0.4064)
			(stroke
				(width 0.1524)
				(type default)
			)
			(layer "F.SilkS")
		)
		(fp_line
			(start -0.7874 -0.4064)
			(end 0.7874 -0.4064)
			(stroke
				(width 0.1524)
				(type default)
			)
			(layer "F.SilkS")
		)
		(fp_line
			(start 0.7874 -0.4064)
			(end 0.7874 0.4064)
			(stroke
				(width 0.1524)
				(type default)
			)
			(layer "F.SilkS")
		)
		(fp_line
			(start -0.67945 0.3048)
			(end -0.67945 -0.305054)
			(stroke
				(width 0.1)
				(type default)
			)
			(layer "F.Fab")
		)
		(fp_line
			(start -0.12065 0.3048)
			(end -0.67945 0.3048)
			(stroke
				(width 0.1)
				(type default)
			)
			(layer "F.Fab")
		)
		(fp_line
			(start 0.120396 0.3048)
			(end 0.120396 0.2794)
			(stroke
				(width 0.1)
				(type default)
			)
			(layer "F.Fab")
		)
		(fp_line
			(start 0.67945 0.3048)
			(end 0.120396 0.3048)
			(stroke
				(width 0.1)
				(type default)
			)
			(layer "F.Fab")
		)
		(fp_line
			(start -0.12065 0.2794)
			(end -0.12065 0.3048)
			(stroke
				(width 0.1)
				(type default)
			)
			(layer "F.Fab")
		)
		(fp_line
			(start 0.120396 0.2794)
			(end -0.12065 0.2794)
			(stroke
				(width 0.1)
				(type default)
			)
			(layer "F.Fab")
		)
		(fp_line
			(start -0.12065 -0.2794)
			(end 0.12065 -0.2794)
			(stroke
				(width 0.1)
				(type default)
			)
			(layer "F.Fab")
		)
		(fp_line
			(start 0.12065 -0.2794)
			(end 0.12065 -0.3048)
			(stroke
				(width 0.1)
				(type default)
			)
			(layer "F.Fab")
		)
		(fp_line
			(start 0.12065 -0.3048)
			(end 0.67945 -0.3048)
			(stroke
				(width 0.1)
				(type default)
			)
			(layer "F.Fab")
		)
		(fp_line
			(start 0.67945 -0.3048)
			(end 0.67945 0.3048)
			(stroke
				(width 0.1)
				(type default)
			)
			(layer "F.Fab")
		)
		(fp_line
			(start -0.67945 -0.305054)
			(end -0.12065 -0.305054)
			(stroke
				(width 0.1)
				(type default)
			)
			(layer "F.Fab")
		)
		(fp_line
			(start -0.12065 -0.305054)
			(end -0.12065 -0.2794)
			(stroke
				(width 0.1)
				(type default)
			)
			(layer "F.Fab")
		)
		(pad "1" smd circle
			(at -0.40005 0 270)
			(size 0 0)
			(layers "F.Cu" "F.Mask" "F.Paste")
			(net "SW_PVCCFA_EHV_FIVRA_CPU1_BOOT1_")
		)
		(pad "2" smd circle
			(at 0.40005 0 270)
			(size 0 0)
			(layers "F.Cu" "F.Mask" "F.Paste")
			(net "SW_PVCCFA_EHV_FIVRA_CPU1_BOOTR1")
		)
	)
	(footprint ""
		(layer "F.Cu")
		(at 31.937452 -162.586162 180)
		(property "Reference" "PR202"
			(at 0 0 180)
			(layer "F.SilkS")
			(hide yes)
			(effects
				(font
					(size 1.27 1.27)
				)
			)
		)
		(property "Value" ""
			(at 0 0 180)
			(layer "F.Fab")
			(effects
				(font
					(size 1.27 1.27)
				)
			)
		)
		(duplicate_pad_numbers_are_jumpers no)
		(fp_line
			(start 0.7874 0.4064)
			(end -0.7874 0.4064)
			(stroke
				(width 0.1524)
				(type default)
			)
			(layer "F.SilkS")
		)
		(fp_line
			(start 0.7874 -0.4064)
			(end 0.7874 0.4064)
			(stroke
				(width 0.1524)
				(type default)
			)
			(layer "F.SilkS")
		)
		(fp_line
			(start -0.7874 0.4064)
			(end -0.7874 -0.4064)
			(stroke
				(width 0.1524)
				(type default)
			)
			(layer "F.SilkS")
		)
		(fp_line
			(start -0.7874 -0.4064)
			(end 0.7874 -0.4064)
			(stroke
				(width 0.1524)
				(type default)
			)
			(layer "F.SilkS")
		)
		(fp_line
			(start 0.67945 0.3048)
			(end 0.120396 0.3048)
			(stroke
				(width 0.1)
				(type default)
			)
			(layer "F.Fab")
		)
		(fp_line
			(start 0.67945 -0.3048)
			(end 0.67945 0.3048)
			(stroke
				(width 0.1)
				(type default)
			)
			(layer "F.Fab")
		)
		(fp_line
			(start 0.12065 -0.2794)
			(end 0.12065 -0.3048)
			(stroke
				(width 0.1)
				(type default)
			)
			(layer "F.Fab")
		)
		(fp_line
			(start 0.12065 -0.3048)
			(end 0.67945 -0.3048)
			(stroke
				(width 0.1)
				(type default)
			)
			(layer "F.Fab")
		)
		(fp_line
			(start 0.120396 0.3048)
			(end 0.120396 0.2794)
			(stroke
				(width 0.1)
				(type default)
			)
			(layer "F.Fab")
		)
		(fp_line
			(start 0.120396 0.2794)
			(end -0.12065 0.2794)
			(stroke
				(width 0.1)
				(type default)
			)
			(layer "F.Fab")
		)
		(fp_line
			(start -0.12065 0.3048)
			(end -0.67945 0.3048)
			(stroke
				(width 0.1)
				(type default)
			)
			(layer "F.Fab")
		)
		(fp_line
			(start -0.12065 0.2794)
			(end -0.12065 0.3048)
			(stroke
				(width 0.1)
				(type default)
			)
			(layer "F.Fab")
		)
		(fp_line
			(start -0.12065 -0.2794)
			(end 0.12065 -0.2794)
			(stroke
				(width 0.1)
				(type default)
			)
			(layer "F.Fab")
		)
		(fp_line
			(start -0.12065 -0.305054)
			(end -0.12065 -0.2794)
			(stroke
				(width 0.1)
				(type default)
			)
			(layer "F.Fab")
		)
		(fp_line
			(start -0.67945 0.3048)
			(end -0.67945 -0.305054)
			(stroke
				(width 0.1)
				(type default)
			)
			(layer "F.Fab")
		)
		(fp_line
			(start -0.67945 -0.305054)
			(end -0.12065 -0.305054)
			(stroke
				(width 0.1)
				(type default)
			)
			(layer "F.Fab")
		)
		(pad "1" smd circle
			(at -0.40005 0 180)
			(size 0 0)
			(layers "F.Cu" "F.Mask" "F.Paste")
			(net "PVCCD_HV_CPU1_VREF")
		)
		(pad "2" smd circle
			(at 0.40005 0 180)
			(size 0 0)
			(layers "F.Cu" "F.Mask" "F.Paste")
			(net "PVCCD_HV_CPU1_ADDR")
		)
	)
	(footprint ""
		(layer "F.Cu")
		(at 33.472374 -393.17549 180)
		(property "Reference" "R4657"
			(at 0 0 180)
			(layer "F.SilkS")
			(hide yes)
			(effects
				(font
					(size 1.27 1.27)
				)
			)
		)
		(property "Value" ""
			(at 0 0 180)
			(layer "F.Fab")
			(effects
				(font
					(size 1.27 1.27)
				)
			)
		)
		(duplicate_pad_numbers_are_jumpers no)
		(fp_line
			(start 0.7874 0.4064)
			(end -0.7874 0.4064)
			(stroke
				(width 0.1524)
				(type default)
			)
			(layer "F.SilkS")
		)
		(fp_line
			(start 0.7874 -0.4064)
			(end 0.7874 0.4064)
			(stroke
				(width 0.1524)
				(type default)
			)
			(layer "F.SilkS")
		)
		(fp_line
			(start -0.7874 0.4064)
			(end -0.7874 -0.4064)
			(stroke
				(width 0.1524)
				(type default)
			)
			(layer "F.SilkS")
		)
		(fp_line
			(start -0.7874 -0.4064)
			(end 0.7874 -0.4064)
			(stroke
				(width 0.1524)
				(type default)
			)
			(layer "F.SilkS")
		)
		(fp_line
			(start 0.67945 0.3048)
			(end 0.120396 0.3048)
			(stroke
				(width 0.1)
				(type default)
			)
			(layer "F.Fab")
		)
		(fp_line
			(start 0.67945 -0.3048)
			(end 0.67945 0.3048)
			(stroke
				(width 0.1)
				(type default)
			)
			(layer "F.Fab")
		)
		(fp_line
			(start 0.12065 -0.2794)
			(end 0.12065 -0.3048)
			(stroke
				(width 0.1)
				(type default)
			)
			(layer "F.Fab")
		)
		(fp_line
			(start 0.12065 -0.3048)
			(end 0.67945 -0.3048)
			(stroke
				(width 0.1)
				(type default)
			)
			(layer "F.Fab")
		)
		(fp_line
			(start 0.120396 0.3048)
			(end 0.120396 0.2794)
			(stroke
				(width 0.1)
				(type default)
			)
			(layer "F.Fab")
		)
		(fp_line
			(start 0.120396 0.2794)
			(end -0.12065 0.2794)
			(stroke
				(width 0.1)
				(type default)
			)
			(layer "F.Fab")
		)
		(fp_line
			(start -0.12065 0.3048)
			(end -0.67945 0.3048)
			(stroke
				(width 0.1)
				(type default)
			)
			(layer "F.Fab")
		)
		(fp_line
			(start -0.12065 0.2794)
			(end -0.12065 0.3048)
			(stroke
				(width 0.1)
				(type default)
			)
			(layer "F.Fab")
		)
		(fp_line
			(start -0.12065 -0.2794)
			(end 0.12065 -0.2794)
			(stroke
				(width 0.1)
				(type default)
			)
			(layer "F.Fab")
		)
		(fp_line
			(start -0.12065 -0.305054)
			(end -0.12065 -0.2794)
			(stroke
				(width 0.1)
				(type default)
			)
			(layer "F.Fab")
		)
		(fp_line
			(start -0.67945 0.3048)
			(end -0.67945 -0.305054)
			(stroke
				(width 0.1)
				(type default)
			)
			(layer "F.Fab")
		)
		(fp_line
			(start -0.67945 -0.305054)
			(end -0.12065 -0.305054)
			(stroke
				(width 0.1)
				(type default)
			)
			(layer "F.Fab")
		)
		(pad "1" smd circle
			(at -0.40005 0 180)
			(size 0 0)
			(layers "F.Cu" "F.Mask" "F.Paste")
			(net "FM_P2E_BUF2_SD_TH")
		)
		(pad "2" smd circle
			(at 0.40005 0 180)
			(size 0 0)
			(layers "F.Cu" "F.Mask" "F.Paste")
			(net "GND")
		)
	)
	(footprint ""
		(layer "F.Cu")
		(at 157.226 -126.365 -90)
		(property "Reference" "R4639"
			(at 0 0 270)
			(layer "F.SilkS")
			(hide yes)
			(effects
				(font
					(size 1.27 1.27)
				)
			)
		)
		(property "Value" ""
			(at 0 0 270)
			(layer "F.Fab")
			(effects
				(font
					(size 1.27 1.27)
				)
			)
		)
		(duplicate_pad_numbers_are_jumpers no)
		(fp_line
			(start -2.234946 0.9271)
			(end -2.234946 -0.9271)
			(stroke
				(width 0.1524)
				(type default)
			)
			(layer "F.SilkS")
		)
		(fp_line
			(start 2.234946 0.9271)
			(end -2.234946 0.9271)
			(stroke
				(width 0.1524)
				(type default)
			)
			(layer "F.SilkS")
		)
		(fp_line
			(start -2.234946 -0.9271)
			(end 2.234946 -0.9271)
			(stroke
				(width 0.1524)
				(type default)
			)
			(layer "F.SilkS")
		)
		(fp_line
			(start 2.234946 -0.9271)
			(end 2.234946 0.9271)
			(stroke
				(width 0.1524)
				(type default)
			)
			(layer "F.SilkS")
		)
		(fp_line
			(start -1.575054 0.824992)
			(end 1.575054 0.824992)
			(stroke
				(width 0.1)
				(type default)
			)
			(layer "F.Fab")
		)
		(fp_line
			(start 1.575054 0.824992)
			(end 1.575054 -0.824992)
			(stroke
				(width 0.1)
				(type default)
			)
			(layer "F.Fab")
		)
		(fp_line
			(start -1.575054 -0.824992)
			(end -1.575054 0.824992)
			(stroke
				(width 0.1)
				(type default)
			)
			(layer "F.Fab")
		)
		(fp_line
			(start 1.575054 -0.824992)
			(end -1.575054 -0.824992)
			(stroke
				(width 0.1)
				(type default)
			)
			(layer "F.Fab")
		)
		(pad "1" smd rect
			(at -1.599946 0 270)
			(size 1.016 1.6002)
			(layers "F.Cu" "F.Mask" "F.Paste")
			(net "P5V")
		)
		(pad "2" smd rect
			(at 1.599946 0 270)
			(size 1.016 1.6002)
			(layers "F.Cu" "F.Mask" "F.Paste")
			(net "VR_P5V_EN_D")
		)
	)
)
